# TIMECARD (Time Appliance Project (Time Card)) — schematic netlist excerpt (pin names and nets, part order shuffled) for the footprints in the layout excerpt that follows; sources: Cadence DE-HDL packaged netlist, KiCad conversion of R4006-B0001-02_R01.brd

C171  CAPACITOR  0.1UF 10V 10%  pkg SMC_0402R_H022  page 14 : \1\ = XP1R0V_FPGA_VCCINT ; \2\ = SG
C157  CAPACITOR  0.1UF 10V 10%  pkg SMC_0402R_H022  page 14 : \1\ = XP3R3V_FPGA ; \2\ = SG

(kicad_pcb
	(version 20260206)
	(generator "pcbnew")
	(generator_version "10.0")
	(general
		(thickness 1.6)
		(legacy_teardrops no)
	)
	(paper "A4")
	(title_block
		(title "timecard-production-celestica-r4006 — R4006-B0001-02_R01.brd")
		(comment 1 "Time Appliance Project (Time Card) / footprints 886-887 of 1113")
	)
	(layers
		(0 "F.Cu" signal "TOP")
		(4 "In1.Cu" signal "L02_GND1")
		(6 "In2.Cu" signal "L03_SIG1")
		(8 "In3.Cu" signal "L04_GND2")
		(10 "In4.Cu" signal "L05_VCC1")
		(12 "In5.Cu" signal "L06_VCC2")
		(14 "In6.Cu" signal "L07_GND3")
		(16 "In7.Cu" signal "L08_SIG2")
		(18 "In8.Cu" signal "L09_GND4")
		(2 "B.Cu" signal "BOTTOM")
		(9 "F.Adhes" user "F.Adhesive")
		(11 "B.Adhes" user "B.Adhesive")
		(13 "F.Paste" user "Package Geometry/Pastemask Top")
		(15 "B.Paste" user "Package Geometry/Pastemask Bottom")
		(5 "F.SilkS" user "Ref Des/Silkscreen Top")
		(7 "B.SilkS" user "Ref Des/Silkscreen Bottom")
		(1 "F.Mask" user "Board Geometry/Soldermask Top")
		(3 "B.Mask" user "Board Geometry/Soldermask Bottom")
		(17 "Dwgs.User" user "User.Drawings")
		(19 "Cmts.User" user "User.Comments")
		(21 "Eco1.User" user "User.Eco1")
		(23 "Eco2.User" user "User.Eco2")
		(25 "Edge.Cuts" user "Board Geometry/Outline")
		(27 "Margin" user)
		(31 "F.CrtYd" user "Package Geometry/Place Bound Top")
		(29 "B.CrtYd" user "Package Geometry/Place Bound Bottom")
		(35 "F.Fab" user "Ref Des/Assembly Top")
		(33 "B.Fab" user "Ref Des/Assembly Bottom")
	)
	(footprint ""
		(layer "B.Cu")
		(at 111.847122 -40.323008 90)
		(property "Reference" "C171"
			(at -1.397508 -42.018712 270)
			(unlocked yes)
			(layer "B.SilkS")
			(effects
				(font
					(size 0.635 0.4064)
					(thickness 0.1524)
				)
				(justify mirror)
			)
		)
		(property "Value" "VAL*"
			(at 0 3.718306 90)
			(unlocked yes)
			(layer "B.Fab")
			(hide yes)
			(effects
				(font
					(size 0.7874 0.5842)
					(thickness 0.127)
				)
				(justify mirror)
			)
		)
		(property "Tolerance" "TOL*"
			(at 0 4.861306 90)
			(unlocked yes)
			(layer "Cmts.User")
			(hide yes)
			(effects
				(font
					(size 0.7874 0.5842)
					(thickness 0.127)
				)
				(justify mirror)
			)
		)
		(property "User Part Number" "PARTNUM*"
			(at 0 2.575306 90)
			(unlocked yes)
			(layer "Cmts.User")
			(hide yes)
			(effects
				(font
					(size 0.7874 0.5842)
					(thickness 0.127)
				)
				(justify mirror)
			)
		)
		(property "Device Type" "CAPACITOR-G105-0B104-CK,0.1UF,A"
			(at 0 1.432306 90)
			(unlocked yes)
			(layer "B.Fab")
			(hide yes)
			(effects
				(font
					(size 0.7874 0.5842)
					(thickness 0.127)
				)
				(justify mirror)
			)
		)
		(duplicate_pad_numbers_are_jumpers no)
		(fp_line
			(start 0.970026 -0.4699)
			(end -0.970026 -0.4699)
			(stroke
				(width 0.1)
				(type default)
			)
			(layer "B.SilkS")
		)
		(fp_line
			(start -0.970026 -0.4699)
			(end -0.970026 0.4699)
			(stroke
				(width 0.1)
				(type default)
			)
			(layer "B.SilkS")
		)
		(fp_line
			(start 0.970026 0.4699)
			(end 0.970026 -0.4699)
			(stroke
				(width 0.1)
				(type default)
			)
			(layer "B.SilkS")
		)
		(fp_line
			(start -0.970026 0.4699)
			(end 0.970026 0.4699)
			(stroke
				(width 0.1)
				(type default)
			)
			(layer "B.SilkS")
		)
		(fp_poly
			(pts
				(xy 0.970026 0.4699) (xy -0.970026 0.4699) (xy -0.970026 -0.4699) (xy 0.970026 -0.4699)
			)
			(stroke
				(width 0)
				(type default)
			)
			(fill no)
			(layer "B.CrtYd")
		)
		(fp_line
			(start 0.508 -0.3048)
			(end -0.508 -0.3048)
			(stroke
				(width 0.1)
				(type default)
			)
			(layer "B.Fab")
		)
		(fp_line
			(start -0.508 -0.3048)
			(end -0.508 0.3048)
			(stroke
				(width 0.1)
				(type default)
			)
			(layer "B.Fab")
		)
		(fp_line
			(start 0.508 0.3048)
			(end 0.508 -0.3048)
			(stroke
				(width 0.1)
				(type default)
			)
			(layer "B.Fab")
		)
		(fp_line
			(start -0.508 0.3048)
			(end 0.508 0.3048)
			(stroke
				(width 0.1)
				(type default)
			)
			(layer "B.Fab")
		)
		(pad "1" smd circle
			(at 0.500126 0 270)
			(size 0.635 0.635)
			(layers "B.Cu" "B.Mask" "B.Paste")
			(net "XP1R0V_FPGA_VCCINT")
		)
		(pad "2" smd circle
			(at -0.500126 0 270)
			(size 0.635 0.635)
			(layers "B.Cu" "B.Mask" "B.Paste")
			(net "SG")
		)
	)
	(footprint ""
		(layer "B.Cu")
		(at 100.346764 -51.823112)
		(property "Reference" "C157"
			(at -2.175764 0.038862 0)
			(unlocked yes)
			(layer "B.SilkS")
			(effects
				(font
					(size 0.635 0.4064)
					(thickness 0.1524)
				)
				(justify mirror)
			)
		)
		(property "Value" "VAL*"
			(at 0 3.718306 0)
			(unlocked yes)
			(layer "B.Fab")
			(hide yes)
			(effects
				(font
					(size 0.7874 0.5842)
					(thickness 0.127)
				)
				(justify mirror)
			)
		)
		(property "Device Type" "CAPACITOR-G105-0B104-CK,0.1UF,A"
			(at 0 1.432306 0)
			(unlocked yes)
			(layer "B.Fab")
			(hide yes)
			(effects
				(font
					(size 0.7874 0.5842)
					(thickness 0.127)
				)
				(justify mirror)
			)
		)
		(property "User Part Number" "PARTNUM*"
			(at 0 2.575306 0)
			(unlocked yes)
			(layer "Cmts.User")
			(hide yes)
			(effects
				(font
					(size 0.7874 0.5842)
					(thickness 0.127)
				)
				(justify mirror)
			)
		)
		(property "Tolerance" "TOL*"
			(at 0 4.861306 0)
			(unlocked yes)
			(layer "Cmts.User")
			(hide yes)
			(effects
				(font
					(size 0.7874 0.5842)
					(thickness 0.127)
				)
				(justify mirror)
			)
		)
		(duplicate_pad_numbers_are_jumpers no)
		(fp_line
			(start -0.970026 -0.4699)
			(end -0.970026 0.4699)
			(stroke
				(width 0.1)
				(type default)
			)
			(layer "B.SilkS")
		)
		(fp_line
			(start -0.970026 0.4699)
			(end 0.970026 0.4699)
			(stroke
				(width 0.1)
				(type default)
			)
			(layer "B.SilkS")
		)
		(fp_line
			(start 0.970026 -0.4699)
			(end -0.970026 -0.4699)
			(stroke
				(width 0.1)
				(type default)
			)
			(layer "B.SilkS")
		)
		(fp_line
			(start 0.970026 0.4699)
			(end 0.970026 -0.4699)
			(stroke
				(width 0.1)
				(type default)
			)
			(layer "B.SilkS")
		)
		(fp_poly
			(pts
				(xy 0.970026 0.4699) (xy -0.970026 0.4699) (xy -0.970026 -0.4699) (xy 0.970026 -0.4699)
			)
			(stroke
				(width 0)
				(type default)
			)
			(fill no)
			(layer "B.CrtYd")
		)
		(fp_line
			(start -0.508 -0.3048)
			(end -0.508 0.3048)
			(stroke
				(width 0.1)
				(type default)
			)
			(layer "B.Fab")
		)
		(fp_line
			(start -0.508 0.3048)
			(end 0.508 0.3048)
			(stroke
				(width 0.1)
				(type default)
			)
			(layer "B.Fab")
		)
		(fp_line
			(start 0.508 -0.3048)
			(end -0.508 -0.3048)
			(stroke
				(width 0.1)
				(type default)
			)
			(layer "B.Fab")
		)
		(fp_line
			(start 0.508 0.3048)
			(end 0.508 -0.3048)
			(stroke
				(width 0.1)
				(type default)
			)
			(layer "B.Fab")
		)
		(pad "1" smd circle
			(at 0.500126 0 180)
			(size 0.635 0.635)
			(layers "B.Cu" "B.Mask" "B.Paste")
			(net "XP3R3V_FPGA")
		)
		(pad "2" smd circle
			(at -0.500126 0 180)
			(size 0.635 0.635)
			(layers "B.Cu" "B.Mask" "B.Paste")
			(net "SG")
		)
	)
)
